# BASEBOARD_FAB2 (Tioga Pass) — schematic netlist excerpt (pin names and nets, part order shuffled) for the footprints in the layout excerpt that follows; sources: Cadence DE-HDL packaged netlist, KiCad conversion of Wiwynn_Tioga_Pass_MB.brd

C2F1  CAP_A  47UF 4V 20% X5R  pkg 0603V  page 225 : A = PVDDQ_GHJ ; B = GND
C9A4  CAP_A  0.1UF 16V 10% X7R  pkg 0402V  page 111 : A = XDP_CPU_PWR_DEBUG_N ; B = GND
C6B8  CAP  0.22UF 16V 10% X7R  pkg 0402  page 105 : A = P3E_CPU0_PE1_PCH_TXP<14> ; B = P3E_CPU0_PE1_PCH_C_TXP<14>

(kicad_pcb
	(version 20260206)
	(generator "pcbnew")
	(generator_version "10.0")
	(general
		(thickness 1.6)
		(legacy_teardrops no)
	)
	(paper "A4")
	(title_block
		(title "Wiwynn_Tioga_Pass_MB.brd")
		(comment 1 "Tioga Pass / footprints 1921-1923 of 4770")
	)
	(layers
		(0 "F.Cu" signal "TOP")
		(4 "In1.Cu" signal "L2GND")
		(6 "In2.Cu" signal "L3")
		(8 "In3.Cu" signal "L4GND")
		(10 "In4.Cu" signal "L5")
		(12 "In5.Cu" signal "L6GND")
		(14 "In6.Cu" signal "L7VCC")
		(16 "In7.Cu" signal "L8VCC")
		(18 "In8.Cu" signal "L9GND")
		(20 "In9.Cu" signal "L10")
		(22 "In10.Cu" signal "L11GND")
		(24 "In11.Cu" signal "L12")
		(26 "In12.Cu" signal "L13GND")
		(2 "B.Cu" signal "BOTTOM")
		(9 "F.Adhes" user "F.Adhesive")
		(11 "B.Adhes" user "B.Adhesive")
		(13 "F.Paste" user "Package Geometry/Pastemask Top")
		(15 "B.Paste" user "Package Geometry/Pastemask Bottom")
		(5 "F.SilkS" user "Ref Des/Silkscreen Top")
		(7 "B.SilkS" user "Ref Des/Silkscreen Bottom")
		(1 "F.Mask" user "Board Geometry/Soldermask Top")
		(3 "B.Mask" user "Board Geometry/Soldermask Bottom")
		(17 "Dwgs.User" user "User.Drawings")
		(19 "Cmts.User" user "User.Comments")
		(21 "Eco1.User" user "User.Eco1")
		(23 "Eco2.User" user "User.Eco2")
		(25 "Edge.Cuts" user "Board Geometry/Outline")
		(27 "Margin" user)
		(31 "F.CrtYd" user "Package Geometry/Place Bound Top")
		(29 "B.CrtYd" user "Package Geometry/Place Bound Bottom")
		(35 "F.Fab" user "Ref Des/Assembly Top")
		(33 "B.Fab" user "Ref Des/Assembly Bottom")
	)
	(footprint ""
		(layer "F.Cu")
		(at 466.09 -147.1295)
		(property "Reference" "C9A4"
			(at 0 0 0)
			(layer "F.SilkS")
			(hide yes)
			(effects
				(font
					(size 1.27 1.27)
				)
			)
		)
		(property "Value" ""
			(at 0 0 0)
			(layer "F.Fab")
			(effects
				(font
					(size 1.27 1.27)
				)
			)
		)
		(duplicate_pad_numbers_are_jumpers no)
		(fp_poly
			(pts
				(xy 0.3048 -0.1016) (xy 0.3048 0.9906) (xy -0.3048 0.9906) (xy -0.3048 -0.1016)
			)
			(stroke
				(width 0)
				(type default)
			)
			(fill no)
			(layer "F.CrtYd")
		)
		(fp_line
			(start -0.3048 -0.1016)
			(end -0.3048 0.9906)
			(stroke
				(width 0.1)
				(type default)
			)
			(layer "F.Fab")
		)
		(fp_line
			(start -0.3048 0.9906)
			(end 0.3048 0.9906)
			(stroke
				(width 0.1)
				(type default)
			)
			(layer "F.Fab")
		)
		(fp_line
			(start 0.3048 -0.1016)
			(end -0.3048 -0.1016)
			(stroke
				(width 0.1)
				(type default)
			)
			(layer "F.Fab")
		)
		(fp_line
			(start 0.3048 0.9906)
			(end 0.3048 -0.1016)
			(stroke
				(width 0.1)
				(type default)
			)
			(layer "F.Fab")
		)
		(pad "1" smd rect
			(at 0 0)
			(size 0.508 0.508)
			(layers "F.Cu" "F.Mask" "F.Paste")
			(net "XDP_CPU_PWR_DEBUG_N")
		)
		(pad "2" smd rect
			(at 0 0.889)
			(size 0.508 0.508)
			(layers "F.Cu" "F.Mask" "F.Paste")
			(net "GND")
		)
		(zone
			(layer "F.Cu")
			(hatch none 0.5)
			(connect_pads
				(clearance 0)
			)
			(min_thickness 0.25)
			(keepout
				(tracks allowed)
				(vias not_allowed)
				(pads allowed)
				(copperpour not_allowed)
				(footprints allowed)
			)
			(placement
				(enabled no)
				(sheetname "")
			)
			(fill
				(thermal_gap 0.5)
				(thermal_bridge_width 0.5)
				(island_removal_mode 0)
			)
			(polygon
				(pts
					(xy 465.836 -146.8755) (xy 466.344 -146.8755) (xy 466.344 -146.4945) (xy 465.836 -146.4945)
				)
			)
		)
		(zone
			(layer "F.Cu")
			(hatch none 0.5)
			(connect_pads
				(clearance 0)
			)
			(min_thickness 0.25)
			(keepout
				(tracks not_allowed)
				(vias allowed)
				(pads allowed)
				(copperpour not_allowed)
				(footprints allowed)
			)
			(placement
				(enabled no)
				(sheetname "")
			)
			(fill
				(thermal_gap 0.5)
				(thermal_bridge_width 0.5)
				(island_removal_mode 0)
			)
			(polygon
				(pts
					(xy 465.836 -146.4945) (xy 466.344 -146.4945) (xy 466.344 -146.8755) (xy 465.836 -146.8755)
				)
			)
		)
	)
	(footprint ""
		(layer "F.Cu")
		(at 78.735174 -26.591006 -45)
		(property "Reference" "C2F1"
			(at 0 0 315)
			(layer "F.SilkS")
			(hide yes)
			(effects
				(font
					(size 1.27 1.27)
				)
			)
		)
		(property "Value" ""
			(at 0 0 315)
			(layer "F.Fab")
			(effects
				(font
					(size 1.27 1.27)
				)
			)
		)
		(duplicate_pad_numbers_are_jumpers no)
		(fp_poly
			(pts
				(xy -0.500021 -0.201359) (xy 0.500231 -0.201359) (xy 0.500231 1.598486) (xy -0.500021 1.598486)
			)
			(stroke
				(width 0)
				(type default)
			)
			(fill no)
			(layer "F.CrtYd")
		)
		(fp_line
			(start -0.500021 1.598486)
			(end -0.5002 -0.201337)
			(stroke
				(width 0.1)
				(type default)
			)
			(layer "F.Fab")
		)
		(fp_line
			(start 0.500021 1.598486)
			(end -0.500021 1.598486)
			(stroke
				(width 0.1)
				(type default)
			)
			(layer "F.Fab")
		)
		(fp_line
			(start -0.5002 -0.201337)
			(end 0.5002 -0.201337)
			(stroke
				(width 0.1)
				(type default)
			)
			(layer "F.Fab")
		)
		(fp_line
			(start 0.5002 -0.201337)
			(end 0.500021 1.598486)
			(stroke
				(width 0.1)
				(type default)
			)
			(layer "F.Fab")
		)
		(pad "1" smd rect
			(at 0 0 225)
			(size 0.889 0.9906)
			(layers "F.Cu" "F.Mask" "F.Paste")
			(net "PVDDQ_GHJ")
		)
		(pad "2" smd rect
			(at 0 1.397 225)
			(size 0.889 0.9906)
			(layers "F.Cu" "F.Mask" "F.Paste")
			(net "GND")
		)
		(zone
			(layer "F.Cu")
			(hatch none 0.5)
			(connect_pads
				(clearance 0)
			)
			(min_thickness 0.25)
			(keepout
				(tracks allowed)
				(vias not_allowed)
				(pads allowed)
				(copperpour not_allowed)
				(footprints allowed)
			)
			(placement
				(enabled no)
				(sheetname "")
			)
			(fill
				(thermal_gap 0.5)
				(thermal_bridge_width 0.5)
				(island_removal_mode 0)
			)
			(polygon
				(pts
					(xy 77.7113 -26.267664) (xy 78.41176 -25.567204) (xy 78.77097 -25.926414) (xy 78.07051 -26.626874)
				)
			)
		)
		(zone
			(layer "F.Cu")
			(hatch none 0.5)
			(connect_pads
				(clearance 0)
			)
			(min_thickness 0.25)
			(keepout
				(tracks not_allowed)
				(vias allowed)
				(pads allowed)
				(copperpour not_allowed)
				(footprints allowed)
			)
			(placement
				(enabled no)
				(sheetname "")
			)
			(fill
				(thermal_gap 0.5)
				(thermal_bridge_width 0.5)
				(island_removal_mode 0)
			)
			(polygon
				(pts
					(xy 77.7113 -26.267664) (xy 78.41176 -25.567204) (xy 78.77097 -25.926414) (xy 78.07051 -26.626874)
				)
			)
		)
	)
	(footprint ""
		(layer "F.Cu")
		(at 324.5485 -122.555 90)
		(property "Reference" "C6B8"
			(at -0.8382 -0.67818 90)
			(unlocked yes)
			(layer "F.SilkS")
			(effects
				(font
					(size 0.4064 0.254)
					(thickness 0.1524)
				)
				(justify left)
			)
		)
		(property "Value" ""
			(at 0 0 90)
			(layer "F.Fab")
			(effects
				(font
					(size 1.27 1.27)
				)
			)
		)
		(duplicate_pad_numbers_are_jumpers no)
		(fp_poly
			(pts
				(xy 0.3048 -0.1016) (xy 0.3048 0.9906) (xy -0.3048 0.9906) (xy -0.3048 -0.1016)
			)
			(stroke
				(width 0)
				(type default)
			)
			(fill no)
			(layer "F.CrtYd")
		)
		(fp_line
			(start 0.3048 -0.1016)
			(end -0.3048 -0.1016)
			(stroke
				(width 0.1)
				(type default)
			)
			(layer "F.Fab")
		)
		(fp_line
			(start -0.3048 -0.1016)
			(end -0.3048 0.9906)
			(stroke
				(width 0.1)
				(type default)
			)
			(layer "F.Fab")
		)
		(fp_line
			(start 0.3048 0.9906)
			(end 0.3048 -0.1016)
			(stroke
				(width 0.1)
				(type default)
			)
			(layer "F.Fab")
		)
		(fp_line
			(start -0.3048 0.9906)
			(end 0.3048 0.9906)
			(stroke
				(width 0.1)
				(type default)
			)
			(layer "F.Fab")
		)
		(pad "1" smd rect
			(at 0 0 90)
			(size 0.508 0.508)
			(layers "F.Cu" "F.Mask" "F.Paste")
			(net "P3E_CPU0_PE1_PCH_TXP<14>")
		)
		(pad "2" smd rect
			(at 0 0.889 90)
			(size 0.508 0.508)
			(layers "F.Cu" "F.Mask" "F.Paste")
			(net "P3E_CPU0_PE1_PCH_C_TXP<14>")
		)
		(zone
			(layer "F.Cu")
			(hatch none 0.5)
			(connect_pads
				(clearance 0)
			)
			(min_thickness 0.25)
			(keepout
				(tracks allowed)
				(vias not_allowed)
				(pads allowed)
				(copperpour not_allowed)
				(footprints allowed)
			)
			(placement
				(enabled no)
				(sheetname "")
			)
			(fill
				(thermal_gap 0.5)
				(thermal_bridge_width 0.5)
				(island_removal_mode 0)
			)
			(polygon
				(pts
					(xy 324.8025 -122.301) (xy 324.8025 -122.809) (xy 325.1835 -122.809) (xy 325.1835 -122.301)
				)
			)
		)
		(zone
			(layer "F.Cu")
			(hatch none 0.5)
			(connect_pads
				(clearance 0)
			)
			(min_thickness 0.25)
			(keepout
				(tracks not_allowed)
				(vias allowed)
				(pads allowed)
				(copperpour not_allowed)
				(footprints allowed)
			)
			(placement
				(enabled no)
				(sheetname "")
			)
			(fill
				(thermal_gap 0.5)
				(thermal_bridge_width 0.5)
				(island_removal_mode 0)
			)
			(polygon
				(pts
					(xy 325.1835 -122.301) (xy 325.1835 -122.809) (xy 324.8025 -122.809) (xy 324.8025 -122.301)
				)
			)
		)
	)
)
